G04*
G04 #@! TF.GenerationSoftware,Altium Limited,Altium Designer,22.4.2 (48)*
G04*
G04 Layer_Color=65535*
%FSLAX25Y25*%
%MOIN*%
G70*
G04*
G04 #@! TF.SameCoordinates,B69760C6-9901-4916-8BAC-4CFDAA04743E*
G04*
G04*
G04 #@! TF.FilePolarity,Positive*
G04*
G01*
G75*
%ADD10C,0.00984*%
%ADD11C,0.03000*%
%ADD12C,0.00787*%
%ADD13C,0.02000*%
%ADD14C,0.00700*%
%ADD15C,0.00394*%
%ADD16C,0.00591*%
%ADD17C,0.00590*%
%ADD18C,0.00591*%
D10*
X55980Y60071D02*
G03*
X55980Y60071I-492J0D01*
G01*
X72193Y64009D02*
G03*
X72193Y64009I-492J0D01*
G01*
X51992Y70042D02*
G03*
X51992Y70042I-492J0D01*
G01*
X206801Y55999D02*
G03*
X206801Y55999I-492J0D01*
G01*
D11*
X86690Y81819D02*
G03*
X86690Y81819I-300J0D01*
G01*
D12*
X55957Y23020D02*
G03*
X55957Y23020I-394J0D01*
G01*
X205475Y10498D02*
Y15664D01*
X210790Y10498D02*
Y15664D01*
X59417Y20838D02*
X64583D01*
X59417Y15523D02*
X64583D01*
X80835Y45444D02*
X85165D01*
X80835Y50956D02*
X85165D01*
X215156Y64435D02*
Y68765D01*
X209644Y64435D02*
Y68765D01*
X222856Y64435D02*
Y68765D01*
X217344Y64435D02*
Y68765D01*
X80935Y72056D02*
X85265D01*
X80935Y66544D02*
X85265D01*
X237243Y75198D02*
Y80364D01*
X242558Y75198D02*
Y80364D01*
X189743Y10498D02*
Y15664D01*
X195057Y10498D02*
Y15664D01*
X56669Y65681D02*
X65331D01*
X56669Y63319D02*
X65331D01*
Y65681D01*
X56669Y63319D02*
Y65681D01*
X208943Y48917D02*
Y54083D01*
X214258Y48917D02*
Y54083D01*
X222458Y48917D02*
Y54083D01*
X217143Y48917D02*
Y54083D01*
X130744Y100335D02*
Y104665D01*
X136256Y100335D02*
Y104665D01*
X71577Y71791D02*
X77375D01*
X71577Y66388D02*
X77375D01*
X74850Y54166D02*
X81150D01*
X74850Y62434D02*
X81150D01*
Y54166D02*
Y62434D01*
X74850Y54166D02*
Y62434D01*
X209278Y40698D02*
X215075D01*
X209278Y46102D02*
X215075D01*
X40244Y72335D02*
Y76665D01*
X45717Y72295D02*
Y76626D01*
X54202Y72601D02*
Y78399D01*
X48798Y72601D02*
Y78399D01*
X73601Y80302D02*
X79399D01*
X73601Y74898D02*
X79399D01*
X47908Y67289D02*
X52092D01*
X47908Y62711D02*
X52092D01*
X56101Y56202D02*
X61899D01*
X56101Y50798D02*
X61899D01*
X66417Y48658D02*
X71583D01*
X66417Y43343D02*
X71583D01*
X59335Y43244D02*
X63665D01*
X59335Y48756D02*
X63665D01*
X196466Y46550D02*
Y52850D01*
X204734Y46550D02*
Y52850D01*
X196466Y46550D02*
X204734D01*
X196466Y52850D02*
X204734D01*
D13*
X258351Y32598D02*
G03*
X258351Y32598I-300J0D01*
G01*
D14*
X7835Y92913D02*
X37756D01*
X7835Y62992D02*
X37756D01*
Y92913D01*
X7835Y62992D02*
Y92913D01*
D15*
X247919Y87599D02*
X250281D01*
X198987Y10301D02*
X201349D01*
X58319Y26957D02*
X60681D01*
X62256Y34043D02*
X66193D01*
Y27744D02*
Y34043D01*
X52807D02*
X56744D01*
X52807Y27744D02*
Y34043D01*
X214719Y10301D02*
X217081D01*
D16*
X80164Y40526D02*
Y43674D01*
X81739D01*
X82263Y43150D01*
Y42100D01*
X81739Y41575D01*
X80164D01*
X81214D02*
X82263Y40526D01*
X83313D02*
X84362D01*
X83838D01*
Y43674D01*
X83313Y43150D01*
X87511Y40526D02*
Y43674D01*
X85937Y42100D01*
X88036D01*
X82564Y73426D02*
Y76574D01*
X84139D01*
X84663Y76050D01*
Y75000D01*
X84139Y74475D01*
X82564D01*
X83614D02*
X84663Y73426D01*
X85713D02*
X86762D01*
X86238D01*
Y76574D01*
X85713Y76050D01*
X88337D02*
X88861Y76574D01*
X89911D01*
X90436Y76050D01*
Y75525D01*
X89911Y75000D01*
X89386D01*
X89911D01*
X90436Y74475D01*
Y73950D01*
X89911Y73426D01*
X88861D01*
X88337Y73950D01*
X214674Y72676D02*
X211526D01*
Y74251D01*
X212051Y74775D01*
X213100D01*
X213625Y74251D01*
Y72676D01*
Y73726D02*
X214674Y74775D01*
X212051Y75825D02*
X211526Y76350D01*
Y77399D01*
X212051Y77924D01*
X212575D01*
X213100Y77399D01*
Y76874D01*
Y77399D01*
X213625Y77924D01*
X214149D01*
X214674Y77399D01*
Y76350D01*
X214149Y75825D01*
X221874Y72676D02*
X218726D01*
Y74251D01*
X219250Y74775D01*
X220300D01*
X220825Y74251D01*
Y72676D01*
Y73726D02*
X221874Y74775D01*
Y77924D02*
Y75825D01*
X219775Y77924D01*
X219250D01*
X218726Y77399D01*
Y76350D01*
X219250Y75825D01*
D17*
X247426Y90027D02*
X250574D01*
Y91601D01*
X250049Y92126D01*
X247951D01*
X247426Y91601D01*
Y90027D01*
X247951Y95274D02*
X247426Y94749D01*
Y93700D01*
X247951Y93175D01*
X248475D01*
X249000Y93700D01*
Y94749D01*
X249525Y95274D01*
X250049D01*
X250574Y94749D01*
Y93700D01*
X250049Y93175D01*
X250574Y96324D02*
Y97373D01*
Y96849D01*
X247426D01*
X247951Y96324D01*
X241174Y83957D02*
X238026D01*
Y85531D01*
X238550Y86056D01*
X239600D01*
X240125Y85531D01*
Y83957D01*
Y85006D02*
X241174Y86056D01*
Y88680D02*
X238026D01*
X239600Y87105D01*
Y89204D01*
D18*
X73176Y52074D02*
Y49450D01*
X73701Y48926D01*
X74751D01*
X75275Y49450D01*
Y52074D01*
X76325Y51550D02*
X76850Y52074D01*
X77899D01*
X78424Y51550D01*
Y51025D01*
X77899Y50500D01*
X77374D01*
X77899D01*
X78424Y49975D01*
Y49450D01*
X77899Y48926D01*
X76850D01*
X76325Y49450D01*
X210026Y61624D02*
X213174D01*
Y60049D01*
X212649Y59525D01*
X211600D01*
X211075Y60049D01*
Y61624D01*
Y60574D02*
X210026Y59525D01*
X213174Y56376D02*
X212649Y57426D01*
X211600Y58475D01*
X210550D01*
X210026Y57951D01*
Y56901D01*
X210550Y56376D01*
X211075D01*
X211600Y56901D01*
Y58475D01*
X218226Y61624D02*
X221374D01*
Y60049D01*
X220849Y59525D01*
X219800D01*
X219275Y60049D01*
Y61624D01*
Y60574D02*
X218226Y59525D01*
X221374Y56376D02*
Y58475D01*
X219800D01*
X220325Y57426D01*
Y56901D01*
X219800Y56376D01*
X218751D01*
X218226Y56901D01*
Y57951D01*
X218751Y58475D01*
X170475Y66549D02*
X169950Y67074D01*
X168901D01*
X168376Y66549D01*
Y64451D01*
X168901Y63926D01*
X169950D01*
X170475Y64451D01*
X173099Y63926D02*
Y67074D01*
X171525Y65500D01*
X173624D01*
X170475Y47049D02*
X169950Y47574D01*
X168901D01*
X168376Y47049D01*
Y44951D01*
X168901Y44426D01*
X169950D01*
X170475Y44951D01*
X171525Y44426D02*
X172574D01*
X172049D01*
Y47574D01*
X171525Y47049D01*
X57376Y75274D02*
Y72650D01*
X57901Y72126D01*
X58951D01*
X59475Y72650D01*
Y75274D01*
X62099Y72126D02*
Y75274D01*
X60525Y73700D01*
X62624D01*
X195967Y64308D02*
Y61684D01*
X196492Y61159D01*
X197541D01*
X198066Y61684D01*
Y64308D01*
X201215Y61159D02*
X199116D01*
X201215Y63258D01*
Y63783D01*
X200690Y64308D01*
X199641D01*
X199116Y63783D01*
X86901Y97074D02*
Y94450D01*
X87426Y93926D01*
X88475D01*
X89000Y94450D01*
Y97074D01*
X90049Y93926D02*
X91099D01*
X90574D01*
Y97074D01*
X90049Y96549D01*
X173826Y19802D02*
Y21901D01*
Y20851D01*
X176974D01*
Y22951D02*
X173826D01*
Y24525D01*
X174351Y25049D01*
X175400D01*
X175925Y24525D01*
Y22951D01*
X174351Y26099D02*
X173826Y26624D01*
Y27673D01*
X174351Y28198D01*
X174875D01*
X175400Y27673D01*
X175925Y28198D01*
X176450D01*
X176974Y27673D01*
Y26624D01*
X176450Y26099D01*
X175925D01*
X175400Y26624D01*
X174875Y26099D01*
X174351D01*
X175400Y26624D02*
Y27673D01*
X168126Y20302D02*
Y22401D01*
Y21351D01*
X171274D01*
Y23450D02*
X168126D01*
Y25025D01*
X168650Y25550D01*
X169700D01*
X170225Y25025D01*
Y23450D01*
X168126Y26599D02*
Y28698D01*
X168650D01*
X170749Y26599D01*
X171274D01*
X162126Y20502D02*
Y22601D01*
Y21551D01*
X165274D01*
Y23651D02*
X162126D01*
Y25225D01*
X162651Y25749D01*
X163700D01*
X164225Y25225D01*
Y23651D01*
X162126Y28898D02*
X162651Y27849D01*
X163700Y26799D01*
X164750D01*
X165274Y27324D01*
Y28373D01*
X164750Y28898D01*
X164225D01*
X163700Y28373D01*
Y26799D01*
X139326Y107002D02*
Y109101D01*
Y108051D01*
X142474D01*
Y110151D02*
X139326D01*
Y111725D01*
X139850Y112250D01*
X140900D01*
X141425Y111725D01*
Y110151D01*
X139326Y115398D02*
Y113299D01*
X140900D01*
X140375Y114349D01*
Y114873D01*
X140900Y115398D01*
X141949D01*
X142474Y114873D01*
Y113824D01*
X141949Y113299D01*
X145226Y106802D02*
Y108901D01*
Y107851D01*
X148374D01*
Y109950D02*
X145226D01*
Y111525D01*
X145750Y112049D01*
X146800D01*
X147325Y111525D01*
Y109950D01*
X148374Y114673D02*
X145226D01*
X146800Y113099D01*
Y115198D01*
X103726Y106302D02*
Y108401D01*
Y107351D01*
X106874D01*
Y109450D02*
X103726D01*
Y111025D01*
X104251Y111549D01*
X105300D01*
X105825Y111025D01*
Y109450D01*
X104251Y112599D02*
X103726Y113124D01*
Y114173D01*
X104251Y114698D01*
X104775D01*
X105300Y114173D01*
Y113649D01*
Y114173D01*
X105825Y114698D01*
X106350D01*
X106874Y114173D01*
Y113124D01*
X106350Y112599D01*
X109426Y107002D02*
Y109101D01*
Y108051D01*
X112574D01*
Y110151D02*
X109426D01*
Y111725D01*
X109950Y112250D01*
X111000D01*
X111525Y111725D01*
Y110151D01*
X112574Y115398D02*
Y113299D01*
X110475Y115398D01*
X109950D01*
X109426Y114873D01*
Y113824D01*
X109950Y113299D01*
X116026Y106827D02*
Y108926D01*
Y107876D01*
X119174D01*
Y109975D02*
X116026D01*
Y111549D01*
X116551Y112074D01*
X117600D01*
X118125Y111549D01*
Y109975D01*
X119174Y113124D02*
Y114173D01*
Y113649D01*
X116026D01*
X116551Y113124D01*
X46064Y38626D02*
Y41774D01*
X47639D01*
X48163Y41249D01*
Y40200D01*
X47639Y39675D01*
X46064D01*
X47114D02*
X48163Y38626D01*
X49213D02*
X50262D01*
X49738D01*
Y41774D01*
X49213Y41249D01*
X53936Y38626D02*
X51837D01*
X53936Y40725D01*
Y41249D01*
X53411Y41774D01*
X52362D01*
X51837Y41249D01*
X67489Y38426D02*
Y41574D01*
X69063D01*
X69588Y41050D01*
Y40000D01*
X69063Y39475D01*
X67489D01*
X68539D02*
X69588Y38426D01*
X70638D02*
X71687D01*
X71162D01*
Y41574D01*
X70638Y41050D01*
X73261Y38426D02*
X74311D01*
X73786D01*
Y41574D01*
X73261Y41050D01*
X57064Y38526D02*
Y41674D01*
X58639D01*
X59163Y41150D01*
Y40100D01*
X58639Y39575D01*
X57064D01*
X58114D02*
X59163Y38526D01*
X60213D02*
X61262D01*
X60738D01*
Y41674D01*
X60213Y41150D01*
X62837D02*
X63362Y41674D01*
X64411D01*
X64936Y41150D01*
Y39050D01*
X64411Y38526D01*
X63362D01*
X62837Y39050D01*
Y41150D01*
X51976Y15906D02*
Y19054D01*
X53550D01*
X54075Y18530D01*
Y17480D01*
X53550Y16955D01*
X51976D01*
X53026D02*
X54075Y15906D01*
X55125Y16431D02*
X55650Y15906D01*
X56699D01*
X57224Y16431D01*
Y18530D01*
X56699Y19054D01*
X55650D01*
X55125Y18530D01*
Y18005D01*
X55650Y17480D01*
X57224D01*
X205476Y5526D02*
Y8674D01*
X207050D01*
X207575Y8150D01*
Y7100D01*
X207050Y6575D01*
X205476D01*
X206526D02*
X207575Y5526D01*
X208625Y8150D02*
X209150Y8674D01*
X210199D01*
X210724Y8150D01*
Y7625D01*
X210199Y7100D01*
X210724Y6575D01*
Y6050D01*
X210199Y5526D01*
X209150D01*
X208625Y6050D01*
Y6575D01*
X209150Y7100D01*
X208625Y7625D01*
Y8150D01*
X209150Y7100D02*
X210199D01*
X189776Y5626D02*
Y8774D01*
X191350D01*
X191875Y8249D01*
Y7200D01*
X191350Y6675D01*
X189776D01*
X190826D02*
X191875Y5626D01*
X192925Y8774D02*
X195024D01*
Y8249D01*
X192925Y6151D01*
Y5626D01*
X135574Y107901D02*
X132426D01*
Y109475D01*
X132950Y110000D01*
X134000D01*
X134525Y109475D01*
Y107901D01*
Y108950D02*
X135574Y110000D01*
Y111049D02*
Y112099D01*
Y111574D01*
X132426D01*
X132950Y111049D01*
X48200Y24351D02*
Y26449D01*
X47675Y26974D01*
X46626D01*
X46101Y26449D01*
Y24351D01*
X46626Y23826D01*
X47675D01*
X47150Y24875D02*
X48200Y23826D01*
X47675D02*
X48200Y24351D01*
X49250Y23826D02*
X50299D01*
X49774D01*
Y26974D01*
X49250Y26449D01*
X49401Y84574D02*
Y81426D01*
X51500D01*
X52549D02*
X53599D01*
X53074D01*
Y84574D01*
X52549Y84049D01*
X33475Y98074D02*
X32426D01*
X32950D01*
Y95451D01*
X32426Y94926D01*
X31901D01*
X31376Y95451D01*
X36624Y94926D02*
X34525D01*
X36624Y97025D01*
Y97549D01*
X36099Y98074D01*
X35050D01*
X34525Y97549D01*
X228166Y66108D02*
X227117D01*
X227641D01*
Y63484D01*
X227117Y62959D01*
X226592D01*
X226067Y63484D01*
X229216Y62959D02*
X230265D01*
X229741D01*
Y66108D01*
X229216Y65583D01*
X213567Y29208D02*
Y26059D01*
X215141D01*
X215666Y26584D01*
Y28683D01*
X215141Y29208D01*
X213567D01*
X218815Y28683D02*
X218290Y29208D01*
X217241D01*
X216716Y28683D01*
Y28158D01*
X217241Y27634D01*
X218290D01*
X218815Y27109D01*
Y26584D01*
X218290Y26059D01*
X217241D01*
X216716Y26584D01*
X219864Y28683D02*
X220389Y29208D01*
X221439D01*
X221963Y28683D01*
Y28158D01*
X221439Y27634D01*
X220914D01*
X221439D01*
X221963Y27109D01*
Y26584D01*
X221439Y26059D01*
X220389D01*
X219864Y26584D01*
X197835Y29208D02*
Y26059D01*
X199409D01*
X199934Y26584D01*
Y28683D01*
X199409Y29208D01*
X197835D01*
X203082Y28683D02*
X202558Y29208D01*
X201508D01*
X200983Y28683D01*
Y28158D01*
X201508Y27634D01*
X202558D01*
X203082Y27109D01*
Y26584D01*
X202558Y26059D01*
X201508D01*
X200983Y26584D01*
X206231Y26059D02*
X204132D01*
X206231Y28158D01*
Y28683D01*
X205706Y29208D01*
X204657D01*
X204132Y28683D01*
X40901Y84574D02*
Y81426D01*
X42475D01*
X43000Y81950D01*
Y84049D01*
X42475Y84574D01*
X40901D01*
X44050Y81426D02*
X45099D01*
X44574D01*
Y84574D01*
X44050Y84049D01*
X40963Y66149D02*
X40439Y66674D01*
X39389D01*
X38864Y66149D01*
Y64051D01*
X39389Y63526D01*
X40439D01*
X40963Y64051D01*
X42013Y63526D02*
X43062D01*
X42538D01*
Y66674D01*
X42013Y66149D01*
X44637D02*
X45162Y66674D01*
X46211D01*
X46736Y66149D01*
Y64051D01*
X46211Y63526D01*
X45162D01*
X44637Y64051D01*
Y66149D01*
X67475Y75249D02*
X66951Y75774D01*
X65901D01*
X65376Y75249D01*
Y73150D01*
X65901Y72626D01*
X66951D01*
X67475Y73150D01*
X68525D02*
X69050Y72626D01*
X70099D01*
X70624Y73150D01*
Y75249D01*
X70099Y75774D01*
X69050D01*
X68525Y75249D01*
Y74725D01*
X69050Y74200D01*
X70624D01*
X75975Y84649D02*
X75450Y85174D01*
X74401D01*
X73876Y84649D01*
Y82551D01*
X74401Y82026D01*
X75450D01*
X75975Y82551D01*
X77025Y84649D02*
X77549Y85174D01*
X78599D01*
X79124Y84649D01*
Y84125D01*
X78599Y83600D01*
X79124Y83075D01*
Y82551D01*
X78599Y82026D01*
X77549D01*
X77025Y82551D01*
Y83075D01*
X77549Y83600D01*
X77025Y84125D01*
Y84649D01*
X77549Y83600D02*
X78599D01*
X65975Y54549D02*
X65451Y55074D01*
X64401D01*
X63876Y54549D01*
Y52451D01*
X64401Y51926D01*
X65451D01*
X65975Y52451D01*
X67025Y55074D02*
X69124D01*
Y54549D01*
X67025Y52451D01*
Y51926D01*
X211575Y38550D02*
X211051Y39074D01*
X210001D01*
X209476Y38550D01*
Y36450D01*
X210001Y35926D01*
X211051D01*
X211575Y36450D01*
X214724Y39074D02*
X213674Y38550D01*
X212625Y37500D01*
Y36450D01*
X213149Y35926D01*
X214199D01*
X214724Y36450D01*
Y36975D01*
X214199Y37500D01*
X212625D01*
X126451Y109975D02*
X125926Y109450D01*
Y108401D01*
X126451Y107876D01*
X128550D01*
X129074Y108401D01*
Y109450D01*
X128550Y109975D01*
X125926Y113124D02*
Y111025D01*
X127500D01*
X126975Y112074D01*
Y112599D01*
X127500Y113124D01*
X128550D01*
X129074Y112599D01*
Y111549D01*
X128550Y111025D01*
X170475Y60549D02*
X169950Y61074D01*
X168901D01*
X168376Y60549D01*
Y58451D01*
X168901Y57926D01*
X169950D01*
X170475Y58451D01*
X171525Y60549D02*
X172049Y61074D01*
X173099D01*
X173624Y60549D01*
Y60025D01*
X173099Y59500D01*
X172574D01*
X173099D01*
X173624Y58975D01*
Y58451D01*
X173099Y57926D01*
X172049D01*
X171525Y58451D01*
X170475Y52549D02*
X169950Y53074D01*
X168901D01*
X168376Y52549D01*
Y50450D01*
X168901Y49926D01*
X169950D01*
X170475Y50450D01*
X173624Y49926D02*
X171525D01*
X173624Y52025D01*
Y52549D01*
X173099Y53074D01*
X172049D01*
X171525Y52549D01*
M02*
